(kicad_pcb
	(version 20260206)
	(generator "pcbnew")
	(generator_version "10.0")
	(general
		(thickness 1.6)
		(legacy_teardrops no)
	)
	(paper "A4")
	(title_block
		(title "Wiwynn_Tioga_Pass_MB.brd")
		(comment 1 "Tioga Pass / footprints 2919-2925 of 4770")
	)
	(layers
		(0 "F.Cu" signal "TOP")
		(4 "In1.Cu" signal "L2GND")
		(6 "In2.Cu" signal "L3")
		(8 "In3.Cu" signal "L4GND")
		(10 "In4.Cu" signal "L5")
		(12 "In5.Cu" signal "L6GND")
		(14 "In6.Cu" signal "L7VCC")
		(16 "In7.Cu" signal "L8VCC")
		(18 "In8.Cu" signal "L9GND")
		(20 "In9.Cu" signal "L10")
		(22 "In10.Cu" signal "L11GND")
		(24 "In11.Cu" signal "L12")
		(26 "In12.Cu" signal "L13GND")
		(2 "B.Cu" signal "BOTTOM")
		(9 "F.Adhes" user "F.Adhesive")
		(11 "B.Adhes" user "B.Adhesive")
		(13 "F.Paste" user "Package Geometry/Pastemask Top")
		(15 "B.Paste" user "Package Geometry/Pastemask Bottom")
		(5 "F.SilkS" user "Ref Des/Silkscreen Top")
		(7 "B.SilkS" user "Ref Des/Silkscreen Bottom")
		(1 "F.Mask" user "Board Geometry/Soldermask Top")
		(3 "B.Mask" user "Board Geometry/Soldermask Bottom")
		(17 "Dwgs.User" user "User.Drawings")
		(19 "Cmts.User" user "User.Comments")
		(21 "Eco1.User" user "User.Eco1")
		(23 "Eco2.User" user "User.Eco2")
		(25 "Edge.Cuts" user "Board Geometry/Outline")
		(27 "Margin" user)
		(31 "F.CrtYd" user "Package Geometry/Place Bound Top")
		(29 "B.CrtYd" user "Package Geometry/Place Bound Bottom")
		(35 "F.Fab" user "Ref Des/Assembly Top")
		(33 "B.Fab" user "Ref Des/Assembly Bottom")
	)
	(footprint ""
		(layer "B.Cu")
		(at 387.5278 -129.99974 180)
		(property "Reference" "R3M9"
			(at 0 0 0)
			(layer "B.SilkS")
			(hide yes)
			(effects
				(font
					(size 1.27 1.27)
				)
				(justify mirror)
			)
		)
		(property "Value" ""
			(at 0 0 0)
			(layer "B.Fab")
			(effects
				(font
					(size 1.27 1.27)
				)
				(justify mirror)
			)
		)
		(duplicate_pad_numbers_are_jumpers no)
		(fp_poly
			(pts
				(xy 0.2794 -0.1016) (xy -0.2794 -0.1016) (xy -0.2794 0.9906) (xy 0.2794 0.9906)
			)
			(stroke
				(width 0)
				(type default)
			)
			(fill no)
			(layer "B.CrtYd")
		)
		(fp_line
			(start 0.2794 0.9906)
			(end -0.2794 0.9906)
			(stroke
				(width 0.1)
				(type default)
			)
			(layer "B.Fab")
		)
		(fp_line
			(start 0.2794 -0.1016)
			(end 0.2794 0.9906)
			(stroke
				(width 0.1)
				(type default)
			)
			(layer "B.Fab")
		)
		(fp_line
			(start -0.2794 0.9906)
			(end -0.2794 -0.1016)
			(stroke
				(width 0.1)
				(type default)
			)
			(layer "B.Fab")
		)
		(fp_line
			(start -0.2794 -0.1016)
			(end 0.2794 -0.1016)
			(stroke
				(width 0.1)
				(type default)
			)
			(layer "B.Fab")
		)
		(pad "1" smd rect
			(at 0 0)
			(size 0.508 0.508)
			(layers "B.Cu" "B.Mask" "B.Paste")
			(net "P2E_SSB_BMC_RX_C_DN")
		)
		(pad "2" smd rect
			(at 0 0.889)
			(size 0.508 0.508)
			(layers "B.Cu" "B.Mask" "B.Paste")
			(net "GND")
		)
		(zone
			(layer "B.Cu")
			(hatch none 0.5)
			(connect_pads
				(clearance 0)
			)
			(min_thickness 0.25)
			(keepout
				(tracks not_allowed)
				(vias allowed)
				(pads allowed)
				(copperpour not_allowed)
				(footprints allowed)
			)
			(placement
				(enabled no)
				(sheetname "")
			)
			(fill
				(thermal_gap 0.5)
				(thermal_bridge_width 0.5)
				(island_removal_mode 0)
			)
			(polygon
				(pts
					(xy 387.2738 -130.63474) (xy 387.7818 -130.63474) (xy 387.7818 -130.25374) (xy 387.2738 -130.25374)
				)
			)
		)
		(zone
			(layer "B.Cu")
			(hatch none 0.5)
			(connect_pads
				(clearance 0)
			)
			(min_thickness 0.25)
			(keepout
				(tracks allowed)
				(vias not_allowed)
				(pads allowed)
				(copperpour not_allowed)
				(footprints allowed)
			)
			(placement
				(enabled no)
				(sheetname "")
			)
			(fill
				(thermal_gap 0.5)
				(thermal_bridge_width 0.5)
				(island_removal_mode 0)
			)
			(polygon
				(pts
					(xy 387.2738 -130.25374) (xy 387.7818 -130.25374) (xy 387.7818 -130.63474) (xy 387.2738 -130.63474)
				)
			)
		)
	)
	(footprint ""
		(layer "B.Cu")
		(at 12.40282 -102.46868 90)
		(property "Reference" "C9N8"
			(at 0 0 90)
			(layer "B.SilkS")
			(hide yes)
			(effects
				(font
					(size 1.27 1.27)
				)
				(justify mirror)
			)
		)
		(property "Value" ""
			(at 0 0 90)
			(layer "B.Fab")
			(effects
				(font
					(size 1.27 1.27)
				)
				(justify mirror)
			)
		)
		(duplicate_pad_numbers_are_jumpers no)
		(fp_poly
			(pts
				(xy -0.3048 -0.1016) (xy -0.3048 0.9906) (xy 0.3048 0.9906) (xy 0.3048 -0.1016)
			)
			(stroke
				(width 0)
				(type default)
			)
			(fill no)
			(layer "B.CrtYd")
		)
		(fp_line
			(start 0.3048 -0.1016)
			(end 0.3048 0.9906)
			(stroke
				(width 0.1)
				(type default)
			)
			(layer "B.Fab")
		)
		(fp_line
			(start -0.3048 -0.1016)
			(end 0.3048 -0.1016)
			(stroke
				(width 0.1)
				(type default)
			)
			(layer "B.Fab")
		)
		(fp_line
			(start 0.3048 0.9906)
			(end -0.3048 0.9906)
			(stroke
				(width 0.1)
				(type default)
			)
			(layer "B.Fab")
		)
		(fp_line
			(start -0.3048 0.9906)
			(end -0.3048 -0.1016)
			(stroke
				(width 0.1)
				(type default)
			)
			(layer "B.Fab")
		)
		(pad "1" smd rect
			(at 0 0 270)
			(size 0.508 0.508)
			(layers "B.Cu" "B.Mask" "B.Paste")
			(net "P3E_CPU1_PE3_MP_C_TXN<14>")
		)
		(pad "2" smd rect
			(at 0 0.889 270)
			(size 0.508 0.508)
			(layers "B.Cu" "B.Mask" "B.Paste")
			(net "P3E_CPU1_PE3_MP_TXN<14>")
		)
		(zone
			(layer "B.Cu")
			(hatch none 0.5)
			(connect_pads
				(clearance 0)
			)
			(min_thickness 0.25)
			(keepout
				(tracks allowed)
				(vias not_allowed)
				(pads allowed)
				(copperpour not_allowed)
				(footprints allowed)
			)
			(placement
				(enabled no)
				(sheetname "")
			)
			(fill
				(thermal_gap 0.5)
				(thermal_bridge_width 0.5)
				(island_removal_mode 0)
			)
			(polygon
				(pts
					(xy 12.65682 -102.72268) (xy 12.65682 -102.21468) (xy 13.03782 -102.21468) (xy 13.03782 -102.72268)
				)
			)
		)
		(zone
			(layer "B.Cu")
			(hatch none 0.5)
			(connect_pads
				(clearance 0)
			)
			(min_thickness 0.25)
			(keepout
				(tracks not_allowed)
				(vias allowed)
				(pads allowed)
				(copperpour not_allowed)
				(footprints allowed)
			)
			(placement
				(enabled no)
				(sheetname "")
			)
			(fill
				(thermal_gap 0.5)
				(thermal_bridge_width 0.5)
				(island_removal_mode 0)
			)
			(polygon
				(pts
					(xy 13.03782 -102.72268) (xy 13.03782 -102.21468) (xy 12.65682 -102.21468) (xy 12.65682 -102.72268)
				)
			)
		)
	)
	(footprint ""
		(layer "B.Cu")
		(at 383.4384 -137.541)
		(property "Reference" "C3L25"
			(at 0 0 0)
			(layer "B.SilkS")
			(hide yes)
			(effects
				(font
					(size 1.27 1.27)
				)
				(justify mirror)
			)
		)
		(property "Value" ""
			(at 0 0 0)
			(layer "B.Fab")
			(effects
				(font
					(size 1.27 1.27)
				)
				(justify mirror)
			)
		)
		(duplicate_pad_numbers_are_jumpers no)
		(fp_poly
			(pts
				(xy 0.4953 -0.2032) (xy -0.4953 -0.2032) (xy -0.4953 1.6002) (xy 0.4953 1.6002)
			)
			(stroke
				(width 0)
				(type default)
			)
			(fill no)
			(layer "B.CrtYd")
		)
		(fp_line
			(start -0.4953 -0.2032)
			(end -0.4953 1.6002)
			(stroke
				(width 0.1)
				(type default)
			)
			(layer "B.Fab")
		)
		(fp_line
			(start -0.4953 1.6002)
			(end 0.4953 1.6002)
			(stroke
				(width 0.1)
				(type default)
			)
			(layer "B.Fab")
		)
		(fp_line
			(start 0.4953 -0.2032)
			(end -0.4953 -0.2032)
			(stroke
				(width 0.1)
				(type default)
			)
			(layer "B.Fab")
		)
		(fp_line
			(start 0.4953 1.6002)
			(end 0.4953 -0.2032)
			(stroke
				(width 0.1)
				(type default)
			)
			(layer "B.Fab")
		)
		(pad "1" smd rect
			(at 0 0 180)
			(size 0.762 0.889)
			(layers "B.Cu" "B.Mask" "B.Paste")
			(net "PVNN_PCH_STBY")
		)
		(pad "2" smd rect
			(at 0 1.397 180)
			(size 0.762 0.889)
			(layers "B.Cu" "B.Mask" "B.Paste")
			(net "GND")
		)
		(zone
			(layer "B.Cu")
			(hatch none 0.5)
			(connect_pads
				(clearance 0)
			)
			(min_thickness 0.25)
			(keepout
				(tracks not_allowed)
				(vias allowed)
				(pads allowed)
				(copperpour not_allowed)
				(footprints allowed)
			)
			(placement
				(enabled no)
				(sheetname "")
			)
			(fill
				(thermal_gap 0.5)
				(thermal_bridge_width 0.5)
				(island_removal_mode 0)
			)
			(polygon
				(pts
					(xy 383.8194 -137.0965) (xy 383.0574 -137.0965) (xy 383.0574 -136.5885) (xy 383.8194 -136.5885)
				)
			)
		)
	)
	(footprint ""
		(layer "B.Cu")
		(at 444.09995 -29.6164)
		(property "Reference" "C25W13"
			(at 0.8382 -0.67818 0)
			(unlocked yes)
			(layer "B.SilkS")
			(effects
				(font
					(size 0.4064 0.254)
					(thickness 0.1524)
				)
				(justify left mirror)
			)
		)
		(property "Value" ""
			(at 0 0 0)
			(layer "B.Fab")
			(effects
				(font
					(size 1.27 1.27)
				)
				(justify mirror)
			)
		)
		(duplicate_pad_numbers_are_jumpers no)
		(fp_poly
			(pts
				(xy -0.3048 -0.1016) (xy -0.3048 0.9906) (xy 0.3048 0.9906) (xy 0.3048 -0.1016)
			)
			(stroke
				(width 0)
				(type default)
			)
			(fill no)
			(layer "B.CrtYd")
		)
		(fp_line
			(start -0.3048 -0.1016)
			(end 0.3048 -0.1016)
			(stroke
				(width 0.1)
				(type default)
			)
			(layer "B.Fab")
		)
		(fp_line
			(start -0.3048 0.9906)
			(end -0.3048 -0.1016)
			(stroke
				(width 0.1)
				(type default)
			)
			(layer "B.Fab")
		)
		(fp_line
			(start 0.3048 -0.1016)
			(end 0.3048 0.9906)
			(stroke
				(width 0.1)
				(type default)
			)
			(layer "B.Fab")
		)
		(fp_line
			(start 0.3048 0.9906)
			(end -0.3048 0.9906)
			(stroke
				(width 0.1)
				(type default)
			)
			(layer "B.Fab")
		)
		(pad "1" smd rect
			(at 0 0 180)
			(size 0.508 0.508)
			(layers "B.Cu" "B.Mask" "B.Paste")
			(net "BMC_M_VREFCA")
		)
		(pad "2" smd rect
			(at 0 0.889 180)
			(size 0.508 0.508)
			(layers "B.Cu" "B.Mask" "B.Paste")
			(net "GND")
		)
		(zone
			(layer "B.Cu")
			(hatch none 0.5)
			(connect_pads
				(clearance 0)
			)
			(min_thickness 0.25)
			(keepout
				(tracks allowed)
				(vias not_allowed)
				(pads allowed)
				(copperpour not_allowed)
				(footprints allowed)
			)
			(placement
				(enabled no)
				(sheetname "")
			)
			(fill
				(thermal_gap 0.5)
				(thermal_bridge_width 0.5)
				(island_removal_mode 0)
			)
			(polygon
				(pts
					(xy 444.35395 -29.3624) (xy 443.84595 -29.3624) (xy 443.84595 -28.9814) (xy 444.35395 -28.9814)
				)
			)
		)
		(zone
			(layer "B.Cu")
			(hatch none 0.5)
			(connect_pads
				(clearance 0)
			)
			(min_thickness 0.25)
			(keepout
				(tracks not_allowed)
				(vias allowed)
				(pads allowed)
				(copperpour not_allowed)
				(footprints allowed)
			)
			(placement
				(enabled no)
				(sheetname "")
			)
			(fill
				(thermal_gap 0.5)
				(thermal_bridge_width 0.5)
				(island_removal_mode 0)
			)
			(polygon
				(pts
					(xy 444.35395 -28.9814) (xy 443.84595 -28.9814) (xy 443.84595 -29.3624) (xy 444.35395 -29.3624)
				)
			)
		)
	)
	(footprint ""
		(layer "B.Cu")
		(at 469.7095 -137.795 -90)
		(property "Reference" "C1L18"
			(at 0 0 90)
			(layer "B.SilkS")
			(hide yes)
			(effects
				(font
					(size 1.27 1.27)
				)
				(justify mirror)
			)
		)
		(property "Value" ""
			(at 0 0 90)
			(layer "B.Fab")
			(effects
				(font
					(size 1.27 1.27)
				)
				(justify mirror)
			)
		)
		(duplicate_pad_numbers_are_jumpers no)
		(fp_poly
			(pts
				(xy -0.3048 -0.1016) (xy -0.3048 0.9906) (xy 0.3048 0.9906) (xy 0.3048 -0.1016)
			)
			(stroke
				(width 0)
				(type default)
			)
			(fill no)
			(layer "B.CrtYd")
		)
		(fp_line
			(start -0.3048 0.9906)
			(end -0.3048 -0.1016)
			(stroke
				(width 0.1)
				(type default)
			)
			(layer "B.Fab")
		)
		(fp_line
			(start 0.3048 0.9906)
			(end -0.3048 0.9906)
			(stroke
				(width 0.1)
				(type default)
			)
			(layer "B.Fab")
		)
		(fp_line
			(start -0.3048 -0.1016)
			(end 0.3048 -0.1016)
			(stroke
				(width 0.1)
				(type default)
			)
			(layer "B.Fab")
		)
		(fp_line
			(start 0.3048 -0.1016)
			(end 0.3048 0.9906)
			(stroke
				(width 0.1)
				(type default)
			)
			(layer "B.Fab")
		)
		(pad "1" smd rect
			(at 0 0 90)
			(size 0.508 0.508)
			(layers "B.Cu" "B.Mask" "B.Paste")
			(net "FP_PWR_BTN_R1_N")
		)
		(pad "2" smd rect
			(at 0 0.889 90)
			(size 0.508 0.508)
			(layers "B.Cu" "B.Mask" "B.Paste")
			(net "GND")
		)
		(zone
			(layer "B.Cu")
			(hatch none 0.5)
			(connect_pads
				(clearance 0)
			)
			(min_thickness 0.25)
			(keepout
				(tracks not_allowed)
				(vias allowed)
				(pads allowed)
				(copperpour not_allowed)
				(footprints allowed)
			)
			(placement
				(enabled no)
				(sheetname "")
			)
			(fill
				(thermal_gap 0.5)
				(thermal_bridge_width 0.5)
				(island_removal_mode 0)
			)
			(polygon
				(pts
					(xy 469.0745 -137.541) (xy 469.0745 -138.049) (xy 469.4555 -138.049) (xy 469.4555 -137.541)
				)
			)
		)
		(zone
			(layer "B.Cu")
			(hatch none 0.5)
			(connect_pads
				(clearance 0)
			)
			(min_thickness 0.25)
			(keepout
				(tracks allowed)
				(vias not_allowed)
				(pads allowed)
				(copperpour not_allowed)
				(footprints allowed)
			)
			(placement
				(enabled no)
				(sheetname "")
			)
			(fill
				(thermal_gap 0.5)
				(thermal_bridge_width 0.5)
				(island_removal_mode 0)
			)
			(polygon
				(pts
					(xy 469.4555 -137.541) (xy 469.4555 -138.049) (xy 469.0745 -138.049) (xy 469.0745 -137.541)
				)
			)
		)
	)
	(footprint ""
		(layer "B.Cu")
		(at 385.051808 -84.729828 180)
		(property "Reference" "R3P5"
			(at 0.8382 -0.67818 180)
			(unlocked yes)
			(layer "B.SilkS")
			(effects
				(font
					(size 0.4064 0.254)
					(thickness 0.1524)
				)
				(justify left mirror)
			)
		)
		(property "Value" ""
			(at 0 0 0)
			(layer "B.Fab")
			(effects
				(font
					(size 1.27 1.27)
				)
				(justify mirror)
			)
		)
		(duplicate_pad_numbers_are_jumpers no)
		(fp_poly
			(pts
				(xy 0.2794 -0.1016) (xy -0.2794 -0.1016) (xy -0.2794 0.9906) (xy 0.2794 0.9906)
			)
			(stroke
				(width 0)
				(type default)
			)
			(fill no)
			(layer "B.CrtYd")
		)
		(fp_line
			(start 0.2794 0.9906)
			(end -0.2794 0.9906)
			(stroke
				(width 0.1)
				(type default)
			)
			(layer "B.Fab")
		)
		(fp_line
			(start 0.2794 -0.1016)
			(end 0.2794 0.9906)
			(stroke
				(width 0.1)
				(type default)
			)
			(layer "B.Fab")
		)
		(fp_line
			(start -0.2794 0.9906)
			(end -0.2794 -0.1016)
			(stroke
				(width 0.1)
				(type default)
			)
			(layer "B.Fab")
		)
		(fp_line
			(start -0.2794 -0.1016)
			(end 0.2794 -0.1016)
			(stroke
				(width 0.1)
				(type default)
			)
			(layer "B.Fab")
		)
		(pad "1" smd rect
			(at 0 0)
			(size 0.508 0.508)
			(layers "B.Cu" "B.Mask" "B.Paste")
			(net "P1V05_PCH_STBY")
		)
		(pad "2" smd rect
			(at 0 0.889)
			(size 0.508 0.508)
			(layers "B.Cu" "B.Mask" "B.Paste")
			(net "FM_PRSNT_2_2_N")
		)
		(zone
			(layer "B.Cu")
			(hatch none 0.5)
			(connect_pads
				(clearance 0)
			)
			(min_thickness 0.25)
			(keepout
				(tracks not_allowed)
				(vias allowed)
				(pads allowed)
				(copperpour not_allowed)
				(footprints allowed)
			)
			(placement
				(enabled no)
				(sheetname "")
			)
			(fill
				(thermal_gap 0.5)
				(thermal_bridge_width 0.5)
				(island_removal_mode 0)
			)
			(polygon
				(pts
					(xy 384.797808 -85.364828) (xy 385.305808 -85.364828) (xy 385.305808 -84.983828) (xy 384.797808 -84.983828)
				)
			)
		)
		(zone
			(layer "B.Cu")
			(hatch none 0.5)
			(connect_pads
				(clearance 0)
			)
			(min_thickness 0.25)
			(keepout
				(tracks allowed)
				(vias not_allowed)
				(pads allowed)
				(copperpour not_allowed)
				(footprints allowed)
			)
			(placement
				(enabled no)
				(sheetname "")
			)
			(fill
				(thermal_gap 0.5)
				(thermal_bridge_width 0.5)
				(island_removal_mode 0)
			)
			(polygon
				(pts
					(xy 384.797808 -84.983828) (xy 385.305808 -84.983828) (xy 385.305808 -85.364828) (xy 384.797808 -85.364828)
				)
			)
		)
	)
	(footprint ""
		(layer "B.Cu")
		(at 459.0034 -127.9144 -90)
		(property "Reference" "U1M7"
			(at 1.40843 -0.70866 0)
			(unlocked yes)
			(layer "B.SilkS")
			(effects
				(font
					(size 0.7874 0.5842)
					(thickness 0.1524)
				)
				(justify left mirror)
			)
		)
		(property "Value" ""
			(at 0 0 90)
			(layer "B.Fab")
			(effects
				(font
					(size 1.27 1.27)
				)
				(justify mirror)
			)
		)
		(duplicate_pad_numbers_are_jumpers no)
		(fp_circle
			(center 0.858266 0.002032)
			(end 0.858266 -0.124968)
			(stroke
				(width 0.254)
				(type default)
			)
			(fill no)
			(layer "B.SilkS")
		)
		(fp_poly
			(pts
				(xy -0.21463 -0.450088) (xy -1.56337 -0.450088) (xy -1.56337 1.75006) (xy -0.21463 1.75006)
			)
			(stroke
				(width 0)
				(type default)
			)
			(fill no)
			(layer "B.CrtYd")
		)
		(fp_line
			(start -1.56337 1.75006)
			(end -0.21463 1.75006)
			(stroke
				(width 0.1)
				(type default)
			)
			(layer "B.Fab")
		)
		(fp_line
			(start -0.21463 1.75006)
			(end -0.21463 -0.450088)
			(stroke
				(width 0.1)
				(type default)
			)
			(layer "B.Fab")
		)
		(fp_line
			(start -1.56337 -0.450088)
			(end -1.56337 1.75006)
			(stroke
				(width 0.1)
				(type default)
			)
			(layer "B.Fab")
		)
		(fp_line
			(start -0.21463 -0.450088)
			(end -1.56337 -0.450088)
			(stroke
				(width 0.1)
				(type default)
			)
			(layer "B.Fab")
		)
		(fp_circle
			(center 0.848614 -0.6477)
			(end 0.848614 -0.7747)
			(stroke
				(width 0.254)
				(type default)
			)
			(fill no)
			(layer "B.Fab")
		)
		(pad "1" smd rect
			(at 0 0 90)
			(size 1.016 0.381)
			(layers "B.Cu" "B.Mask" "B.Paste")
			(net "XDP_CPU0_TDO")
		)
		(pad "2" smd rect
			(at 0 0.649986 90)
			(size 1.016 0.381)
			(layers "B.Cu" "B.Mask" "B.Paste")
			(net "GND")
		)
		(pad "3" smd rect
			(at 0 1.299972 90)
			(size 1.016 0.381)
			(layers "B.Cu" "B.Mask" "B.Paste")
			(net "XDP_CPU1_TDO")
		)
		(pad "4" smd rect
			(at -1.778 1.299972 90)
			(size 1.016 0.381)
			(layers "B.Cu" "B.Mask" "B.Paste")
			(net "XDP_CPU_TDO")
		)
		(pad "5" smd rect
			(at -1.778 0.649986 90)
			(size 1.016 0.381)
			(layers "B.Cu" "B.Mask" "B.Paste")
			(net "P3V3_STBY")
		)
		(pad "6" smd rect
			(at -1.778 0 90)
			(size 1.016 0.381)
			(layers "B.Cu" "B.Mask" "B.Paste")
			(net "FM_CPU1_SKTOCC_LVT3_N")
		)
	)
)
